# T6G (Grand Teton) — schematic netlist excerpt (pin names and nets, part order shuffled) for the footprints in the layout excerpt that follows; sources: Cadence DE-HDL packaged netlist, KiCad conversion of 04192023_DAF0TMB3IC0_F0TG_MB_C_brd_V02_OCP.brd

R76  Q_RES  0 5% CHIP  pkg 0402LF  page 132 : A = NCSI_BMC_TXD1_R ; B = RMII_BMC_OCP_TXD_1
C1088  Q_CAP  0.1UF 25V 10% X7R  pkg 0402  page 258 : A = PVDD18_S5_P0_ADC_TIC ; B = GND
R1514  Q_RES  0 5% CHIP  pkg 0201LF  page 184 : A = SMB_MUX_RT_R1_SCL ; B = SMB_MUX_RT_R2_SCL

(kicad_pcb
	(version 20260206)
	(generator "pcbnew")
	(generator_version "10.0")
	(general
		(thickness 1.6)
		(legacy_teardrops no)
	)
	(paper "A4")
	(title_block
		(title "04192023_DAF0TMB3IC0_F0TG_MB_C_brd_V02_OCP.brd")
		(comment 1 "Grand Teton / footprints 7040-7042 of 8354")
	)
	(layers
		(0 "F.Cu" signal "TOP")
		(4 "In1.Cu" signal "GND")
		(6 "In2.Cu" signal "IN1")
		(8 "In3.Cu" signal "GND1")
		(10 "In4.Cu" signal "IN2")
		(12 "In5.Cu" signal "GND2")
		(14 "In6.Cu" signal "IN3")
		(16 "In7.Cu" signal "GND3")
		(18 "In8.Cu" signal "VCC")
		(20 "In9.Cu" signal "VCC1")
		(22 "In10.Cu" signal "GND4")
		(24 "In11.Cu" signal "IN4")
		(26 "In12.Cu" signal "GND5")
		(28 "In13.Cu" signal "IN5")
		(30 "In14.Cu" signal "GND6")
		(32 "In15.Cu" signal "IN6")
		(34 "In16.Cu" signal "GND7")
		(2 "B.Cu" signal "BOTTOM")
		(9 "F.Adhes" user "F.Adhesive")
		(11 "B.Adhes" user "B.Adhesive")
		(13 "F.Paste" user "Package Geometry/Pastemask Top")
		(15 "B.Paste" user "Package Geometry/Pastemask Bottom")
		(5 "F.SilkS" user "Ref Des/Silkscreen Top")
		(7 "B.SilkS" user "Ref Des/Silkscreen Bottom")
		(1 "F.Mask" user "Board Geometry/Soldermask Top")
		(3 "B.Mask" user "Board Geometry/Soldermask Bottom")
		(17 "Dwgs.User" user "User.Drawings")
		(19 "Cmts.User" user "User.Comments")
		(21 "Eco1.User" user "User.Eco1")
		(23 "Eco2.User" user "User.Eco2")
		(25 "Edge.Cuts" user "Board Geometry/Outline")
		(27 "Margin" user)
		(31 "F.CrtYd" user "Package Geometry/Place Bound Top")
		(29 "B.CrtYd" user "Package Geometry/Place Bound Bottom")
		(35 "F.Fab" user "Ref Des/Assembly Top")
		(33 "B.Fab" user "Ref Des/Assembly Bottom")
	)
	(footprint ""
		(layer "B.Cu")
		(at 228.410516 -328.638662 180)
		(property "Reference" "C1088"
			(at 0 0 0)
			(layer "B.SilkS")
			(hide yes)
			(effects
				(font
					(size 1.27 1.27)
				)
				(justify mirror)
			)
		)
		(property "Value" ""
			(at 0 0 0)
			(layer "B.Fab")
			(effects
				(font
					(size 1.27 1.27)
				)
				(justify mirror)
			)
		)
		(duplicate_pad_numbers_are_jumpers no)
		(fp_line
			(start 0.7874 0.4064)
			(end 0.7874 -0.4064)
			(stroke
				(width 0.1524)
				(type default)
			)
			(layer "B.SilkS")
		)
		(fp_line
			(start 0.7874 -0.4064)
			(end -0.7874 -0.4064)
			(stroke
				(width 0.1524)
				(type default)
			)
			(layer "B.SilkS")
		)
		(fp_line
			(start -0.7874 0.4064)
			(end 0.7874 0.4064)
			(stroke
				(width 0.1524)
				(type default)
			)
			(layer "B.SilkS")
		)
		(fp_line
			(start -0.7874 -0.4064)
			(end -0.7874 0.4064)
			(stroke
				(width 0.1524)
				(type default)
			)
			(layer "B.SilkS")
		)
		(fp_line
			(start 0.67945 0.3048)
			(end 0.67945 -0.305054)
			(stroke
				(width 0.1)
				(type default)
			)
			(layer "B.Fab")
		)
		(fp_line
			(start 0.67945 -0.305054)
			(end 0.12065 -0.305054)
			(stroke
				(width 0.1)
				(type default)
			)
			(layer "B.Fab")
		)
		(fp_line
			(start 0.12065 0.3048)
			(end 0.67945 0.3048)
			(stroke
				(width 0.1)
				(type default)
			)
			(layer "B.Fab")
		)
		(fp_line
			(start 0.12065 0.2794)
			(end 0.12065 0.3048)
			(stroke
				(width 0.1)
				(type default)
			)
			(layer "B.Fab")
		)
		(fp_line
			(start 0.12065 -0.2794)
			(end -0.12065 -0.2794)
			(stroke
				(width 0.1)
				(type default)
			)
			(layer "B.Fab")
		)
		(fp_line
			(start 0.12065 -0.305054)
			(end 0.12065 -0.2794)
			(stroke
				(width 0.1)
				(type default)
			)
			(layer "B.Fab")
		)
		(fp_line
			(start -0.120396 0.3048)
			(end -0.120396 0.2794)
			(stroke
				(width 0.1)
				(type default)
			)
			(layer "B.Fab")
		)
		(fp_line
			(start -0.120396 0.2794)
			(end 0.12065 0.2794)
			(stroke
				(width 0.1)
				(type default)
			)
			(layer "B.Fab")
		)
		(fp_line
			(start -0.12065 -0.2794)
			(end -0.12065 -0.3048)
			(stroke
				(width 0.1)
				(type default)
			)
			(layer "B.Fab")
		)
		(fp_line
			(start -0.12065 -0.3048)
			(end -0.67945 -0.3048)
			(stroke
				(width 0.1)
				(type default)
			)
			(layer "B.Fab")
		)
		(fp_line
			(start -0.67945 0.3048)
			(end -0.120396 0.3048)
			(stroke
				(width 0.1)
				(type default)
			)
			(layer "B.Fab")
		)
		(fp_line
			(start -0.67945 -0.3048)
			(end -0.67945 0.3048)
			(stroke
				(width 0.1)
				(type default)
			)
			(layer "B.Fab")
		)
		(pad "1" smd circle
			(at 0.40005 0)
			(size 0 0)
			(layers "B.Cu" "B.Mask" "B.Paste")
			(net "PVDD18_S5_P0_ADC_TIC")
		)
		(pad "2" smd circle
			(at -0.40005 0)
			(size 0 0)
			(layers "B.Cu" "B.Mask" "B.Paste")
			(net "GND")
		)
	)
	(footprint ""
		(layer "B.Cu")
		(at 215.521286 -73.050908)
		(property "Reference" "R76"
			(at 0 0 0)
			(layer "B.SilkS")
			(hide yes)
			(effects
				(font
					(size 1.27 1.27)
				)
				(justify mirror)
			)
		)
		(property "Value" ""
			(at 0 0 0)
			(layer "B.Fab")
			(effects
				(font
					(size 1.27 1.27)
				)
				(justify mirror)
			)
		)
		(duplicate_pad_numbers_are_jumpers no)
		(fp_line
			(start -0.7874 -0.4064)
			(end -0.7874 0.4064)
			(stroke
				(width 0.1524)
				(type default)
			)
			(layer "B.SilkS")
		)
		(fp_line
			(start -0.7874 0.4064)
			(end 0.7874 0.4064)
			(stroke
				(width 0.1524)
				(type default)
			)
			(layer "B.SilkS")
		)
		(fp_line
			(start 0.7874 -0.4064)
			(end -0.7874 -0.4064)
			(stroke
				(width 0.1524)
				(type default)
			)
			(layer "B.SilkS")
		)
		(fp_line
			(start 0.7874 0.4064)
			(end 0.7874 -0.4064)
			(stroke
				(width 0.1524)
				(type default)
			)
			(layer "B.SilkS")
		)
		(fp_line
			(start -0.67945 -0.3048)
			(end -0.67945 0.3048)
			(stroke
				(width 0.1)
				(type default)
			)
			(layer "B.Fab")
		)
		(fp_line
			(start -0.67945 0.3048)
			(end -0.120396 0.3048)
			(stroke
				(width 0.1)
				(type default)
			)
			(layer "B.Fab")
		)
		(fp_line
			(start -0.12065 -0.3048)
			(end -0.67945 -0.3048)
			(stroke
				(width 0.1)
				(type default)
			)
			(layer "B.Fab")
		)
		(fp_line
			(start -0.12065 -0.2794)
			(end -0.12065 -0.3048)
			(stroke
				(width 0.1)
				(type default)
			)
			(layer "B.Fab")
		)
		(fp_line
			(start -0.120396 0.2794)
			(end 0.12065 0.2794)
			(stroke
				(width 0.1)
				(type default)
			)
			(layer "B.Fab")
		)
		(fp_line
			(start -0.120396 0.3048)
			(end -0.120396 0.2794)
			(stroke
				(width 0.1)
				(type default)
			)
			(layer "B.Fab")
		)
		(fp_line
			(start 0.12065 -0.305054)
			(end 0.12065 -0.2794)
			(stroke
				(width 0.1)
				(type default)
			)
			(layer "B.Fab")
		)
		(fp_line
			(start 0.12065 -0.2794)
			(end -0.12065 -0.2794)
			(stroke
				(width 0.1)
				(type default)
			)
			(layer "B.Fab")
		)
		(fp_line
			(start 0.12065 0.2794)
			(end 0.12065 0.3048)
			(stroke
				(width 0.1)
				(type default)
			)
			(layer "B.Fab")
		)
		(fp_line
			(start 0.12065 0.3048)
			(end 0.67945 0.3048)
			(stroke
				(width 0.1)
				(type default)
			)
			(layer "B.Fab")
		)
		(fp_line
			(start 0.67945 -0.305054)
			(end 0.12065 -0.305054)
			(stroke
				(width 0.1)
				(type default)
			)
			(layer "B.Fab")
		)
		(fp_line
			(start 0.67945 0.3048)
			(end 0.67945 -0.305054)
			(stroke
				(width 0.1)
				(type default)
			)
			(layer "B.Fab")
		)
		(pad "1" smd circle
			(at 0.40005 0 180)
			(size 0 0)
			(layers "B.Cu" "B.Mask" "B.Paste")
			(net "NCSI_BMC_TXD1_R")
		)
		(pad "2" smd circle
			(at -0.40005 0 180)
			(size 0 0)
			(layers "B.Cu" "B.Mask" "B.Paste")
			(net "RMII_BMC_OCP_TXD_1")
		)
	)
	(footprint ""
		(layer "B.Cu")
		(at 245.7704 -332.0796 180)
		(property "Reference" "R1514"
			(at 0 0 0)
			(layer "B.SilkS")
			(hide yes)
			(effects
				(font
					(size 1.27 1.27)
				)
				(justify mirror)
			)
		)
		(property "Value" ""
			(at 0 0 0)
			(layer "B.Fab")
			(effects
				(font
					(size 1.27 1.27)
				)
				(justify mirror)
			)
		)
		(duplicate_pad_numbers_are_jumpers no)
		(fp_line
			(start 0.32512 0.175006)
			(end 0.32512 -0.175006)
			(stroke
				(width 0.1)
				(type default)
			)
			(layer "B.Fab")
		)
		(fp_line
			(start 0.32512 -0.175006)
			(end -0.32512 -0.175006)
			(stroke
				(width 0.1)
				(type default)
			)
			(layer "B.Fab")
		)
		(fp_line
			(start -0.32512 0.175006)
			(end 0.32512 0.175006)
			(stroke
				(width 0.1)
				(type default)
			)
			(layer "B.Fab")
		)
		(fp_line
			(start -0.32512 -0.175006)
			(end -0.32512 0.175006)
			(stroke
				(width 0.1)
				(type default)
			)
			(layer "B.Fab")
		)
		(pad "1" smd rect
			(at 0.2667 0)
			(size 0.3048 0.381)
			(layers "B.Cu" "B.Mask" "B.Paste")
			(net "SMB_MUX_RT_R1_SCL")
		)
		(pad "2" smd rect
			(at -0.2667 0 180)
			(size 0.3048 0.381)
			(layers "B.Cu" "B.Mask" "B.Paste")
			(net "SMB_MUX_RT_R2_SCL")
		)
	)
)
